(kicad_pcb
	(version 20260206)
	(generator "pcbnew")
	(generator_version "10.0")
	(general
		(thickness 1.6)
		(legacy_teardrops no)
	)
	(paper "A4")
	(title_block
		(title "01162023_DA0F0TEBIF0_F0T_Expander_BD_F_brd_V02_OCP.brd")
		(comment 1 "Grand Teton / footprints 6806-6812 of 9728")
	)
	(layers
		(0 "F.Cu" signal "TOP")
		(4 "In1.Cu" signal "GND")
		(6 "In2.Cu" signal "VCC")
		(8 "In3.Cu" signal "VCC1")
		(10 "In4.Cu" signal "GND1")
		(12 "In5.Cu" signal "IN1")
		(14 "In6.Cu" signal "GND2")
		(16 "In7.Cu" signal "IN2")
		(18 "In8.Cu" signal "GND3")
		(20 "In9.Cu" signal "IN3")
		(22 "In10.Cu" signal "GND4")
		(24 "In11.Cu" signal "IN4")
		(26 "In12.Cu" signal "GND5")
		(28 "In13.Cu" signal "IN5")
		(30 "In14.Cu" signal "GND6")
		(32 "In15.Cu" signal "IN6")
		(34 "In16.Cu" signal "GND7")
		(2 "B.Cu" signal "BOTTOM")
		(9 "F.Adhes" user "F.Adhesive")
		(11 "B.Adhes" user "B.Adhesive")
		(13 "F.Paste" user "Package Geometry/Pastemask Top")
		(15 "B.Paste" user "Package Geometry/Pastemask Bottom")
		(5 "F.SilkS" user "Ref Des/Silkscreen Top")
		(7 "B.SilkS" user "Ref Des/Silkscreen Bottom")
		(1 "F.Mask" user "Board Geometry/Soldermask Top")
		(3 "B.Mask" user "Board Geometry/Soldermask Bottom")
		(17 "Dwgs.User" user "User.Drawings")
		(19 "Cmts.User" user "User.Comments")
		(21 "Eco1.User" user "User.Eco1")
		(23 "Eco2.User" user "User.Eco2")
		(25 "Edge.Cuts" user "Board Geometry/Outline")
		(27 "Margin" user)
		(31 "F.CrtYd" user "Package Geometry/Place Bound Top")
		(29 "B.CrtYd" user "Package Geometry/Place Bound Bottom")
		(35 "F.Fab" user "Ref Des/Assembly Top")
		(33 "B.Fab" user "Ref Des/Assembly Bottom")
	)
	(footprint ""
		(layer "F.Cu")
		(at 136.531096 -196.821806 180)
		(property "Reference" "R916"
			(at 0 0 180)
			(layer "F.SilkS")
			(hide yes)
			(effects
				(font
					(size 1.27 1.27)
				)
			)
		)
		(property "Value" ""
			(at 0 0 180)
			(layer "F.Fab")
			(effects
				(font
					(size 1.27 1.27)
				)
			)
		)
		(duplicate_pad_numbers_are_jumpers no)
		(fp_line
			(start 1.2954 0.5842)
			(end -1.2954 0.5842)
			(stroke
				(width 0.1524)
				(type default)
			)
			(layer "F.SilkS")
		)
		(fp_line
			(start 1.2954 -0.5842)
			(end 1.2954 0.5842)
			(stroke
				(width 0.1524)
				(type default)
			)
			(layer "F.SilkS")
		)
		(fp_line
			(start -1.2954 0.5842)
			(end -1.2954 -0.5842)
			(stroke
				(width 0.1524)
				(type default)
			)
			(layer "F.SilkS")
		)
		(fp_line
			(start -1.2954 -0.5842)
			(end 1.2954 -0.5842)
			(stroke
				(width 0.1524)
				(type default)
			)
			(layer "F.SilkS")
		)
		(fp_line
			(start 1.1938 0.4064)
			(end 0.8636 0.4064)
			(stroke
				(width 0.1)
				(type default)
			)
			(layer "F.Fab")
		)
		(fp_line
			(start 1.1938 -0.406654)
			(end 1.1938 0.4064)
			(stroke
				(width 0.1)
				(type default)
			)
			(layer "F.Fab")
		)
		(fp_line
			(start 0.8636 0.4572)
			(end -0.8636 0.4572)
			(stroke
				(width 0.1)
				(type default)
			)
			(layer "F.Fab")
		)
		(fp_line
			(start 0.8636 0.4064)
			(end 0.8636 0.4572)
			(stroke
				(width 0.1)
				(type default)
			)
			(layer "F.Fab")
		)
		(fp_line
			(start 0.8636 -0.406654)
			(end 1.1938 -0.406654)
			(stroke
				(width 0.1)
				(type default)
			)
			(layer "F.Fab")
		)
		(fp_line
			(start 0.8636 -0.4572)
			(end 0.8636 -0.406654)
			(stroke
				(width 0.1)
				(type default)
			)
			(layer "F.Fab")
		)
		(fp_line
			(start -0.8636 0.4572)
			(end -0.8636 0.4318)
			(stroke
				(width 0.1)
				(type default)
			)
			(layer "F.Fab")
		)
		(fp_line
			(start -0.8636 0.4318)
			(end -0.8636 0.4064)
			(stroke
				(width 0.1)
				(type default)
			)
			(layer "F.Fab")
		)
		(fp_line
			(start -0.8636 0.4064)
			(end -1.1938 0.4064)
			(stroke
				(width 0.1)
				(type default)
			)
			(layer "F.Fab")
		)
		(fp_line
			(start -0.8636 -0.406654)
			(end -0.8636 -0.4572)
			(stroke
				(width 0.1)
				(type default)
			)
			(layer "F.Fab")
		)
		(fp_line
			(start -0.8636 -0.4572)
			(end 0.8636 -0.4572)
			(stroke
				(width 0.1)
				(type default)
			)
			(layer "F.Fab")
		)
		(fp_line
			(start -1.1938 0.4064)
			(end -1.1938 -0.406654)
			(stroke
				(width 0.1)
				(type default)
			)
			(layer "F.Fab")
		)
		(fp_line
			(start -1.1938 -0.406654)
			(end -0.8636 -0.406654)
			(stroke
				(width 0.1)
				(type default)
			)
			(layer "F.Fab")
		)
		(pad "1" smd rect
			(at -0.7366 0 90)
			(size 0.7112 0.8128)
			(layers "F.Cu" "F.Mask" "F.Paste")
			(net "OSC_CLI_OUT")
		)
		(pad "2" smd rect
			(at 0.7366 0 90)
			(size 0.7112 0.8128)
			(layers "F.Cu" "F.Mask" "F.Paste")
			(net "OSC_CLI_IN")
		)
	)
	(footprint ""
		(layer "F.Cu")
		(at 80.019398 -147.104608 180)
		(property "Reference" "C11"
			(at 0 0 180)
			(layer "F.SilkS")
			(hide yes)
			(effects
				(font
					(size 1.27 1.27)
				)
			)
		)
		(property "Value" ""
			(at 0 0 180)
			(layer "F.Fab")
			(effects
				(font
					(size 1.27 1.27)
				)
			)
		)
		(duplicate_pad_numbers_are_jumpers no)
		(fp_line
			(start 0.299974 0.150114)
			(end -0.299974 0.150114)
			(stroke
				(width 0.1)
				(type default)
			)
			(layer "F.Fab")
		)
		(fp_line
			(start 0.299974 -0.150114)
			(end 0.299974 0.150114)
			(stroke
				(width 0.1)
				(type default)
			)
			(layer "F.Fab")
		)
		(fp_line
			(start -0.299974 0.150114)
			(end -0.299974 -0.150114)
			(stroke
				(width 0.1)
				(type default)
			)
			(layer "F.Fab")
		)
		(fp_line
			(start -0.299974 -0.150114)
			(end 0.299974 -0.150114)
			(stroke
				(width 0.1)
				(type default)
			)
			(layer "F.Fab")
		)
		(pad "1" smd rect
			(at -0.2667 0 180)
			(size 0.3048 0.381)
			(layers "F.Cu" "F.Mask" "F.Paste")
			(net "P5E_PEX0_STN0_TX_DP<10>")
		)
		(pad "2" smd rect
			(at 0.2667 0 180)
			(size 0.3048 0.381)
			(layers "F.Cu" "F.Mask" "F.Paste")
			(net "P5E_PEX0_STN0_TX_C_DP<10>")
		)
	)
	(footprint ""
		(layer "F.Cu")
		(at 146.473926 -27.006296 -90)
		(property "Reference" "PC926"
			(at 0 0 270)
			(layer "F.SilkS")
			(hide yes)
			(effects
				(font
					(size 1.27 1.27)
				)
			)
		)
		(property "Value" ""
			(at 0 0 270)
			(layer "F.Fab")
			(effects
				(font
					(size 1.27 1.27)
				)
			)
		)
		(duplicate_pad_numbers_are_jumpers no)
		(fp_line
			(start -0.7874 0.4064)
			(end -0.7874 -0.4064)
			(stroke
				(width 0.1524)
				(type default)
			)
			(layer "F.SilkS")
		)
		(fp_line
			(start 0.7874 0.4064)
			(end -0.7874 0.4064)
			(stroke
				(width 0.1524)
				(type default)
			)
			(layer "F.SilkS")
		)
		(fp_line
			(start -0.7874 -0.4064)
			(end 0.7874 -0.4064)
			(stroke
				(width 0.1524)
				(type default)
			)
			(layer "F.SilkS")
		)
		(fp_line
			(start 0.7874 -0.4064)
			(end 0.7874 0.4064)
			(stroke
				(width 0.1524)
				(type default)
			)
			(layer "F.SilkS")
		)
		(fp_line
			(start -0.67945 0.3048)
			(end -0.67945 -0.305054)
			(stroke
				(width 0.1)
				(type default)
			)
			(layer "F.Fab")
		)
		(fp_line
			(start -0.12065 0.3048)
			(end -0.67945 0.3048)
			(stroke
				(width 0.1)
				(type default)
			)
			(layer "F.Fab")
		)
		(fp_line
			(start 0.120396 0.3048)
			(end 0.120396 0.2794)
			(stroke
				(width 0.1)
				(type default)
			)
			(layer "F.Fab")
		)
		(fp_line
			(start 0.67945 0.3048)
			(end 0.120396 0.3048)
			(stroke
				(width 0.1)
				(type default)
			)
			(layer "F.Fab")
		)
		(fp_line
			(start -0.12065 0.2794)
			(end -0.12065 0.3048)
			(stroke
				(width 0.1)
				(type default)
			)
			(layer "F.Fab")
		)
		(fp_line
			(start 0.120396 0.2794)
			(end -0.12065 0.2794)
			(stroke
				(width 0.1)
				(type default)
			)
			(layer "F.Fab")
		)
		(fp_line
			(start -0.12065 -0.2794)
			(end 0.12065 -0.2794)
			(stroke
				(width 0.1)
				(type default)
			)
			(layer "F.Fab")
		)
		(fp_line
			(start 0.12065 -0.2794)
			(end 0.12065 -0.3048)
			(stroke
				(width 0.1)
				(type default)
			)
			(layer "F.Fab")
		)
		(fp_line
			(start 0.12065 -0.3048)
			(end 0.67945 -0.3048)
			(stroke
				(width 0.1)
				(type default)
			)
			(layer "F.Fab")
		)
		(fp_line
			(start 0.67945 -0.3048)
			(end 0.67945 0.3048)
			(stroke
				(width 0.1)
				(type default)
			)
			(layer "F.Fab")
		)
		(fp_line
			(start -0.67945 -0.305054)
			(end -0.12065 -0.305054)
			(stroke
				(width 0.1)
				(type default)
			)
			(layer "F.Fab")
		)
		(fp_line
			(start -0.12065 -0.305054)
			(end -0.12065 -0.2794)
			(stroke
				(width 0.1)
				(type default)
			)
			(layer "F.Fab")
		)
		(pad "1" smd circle
			(at -0.40005 0 270)
			(size 0 0)
			(layers "F.Cu" "F.Mask" "F.Paste")
			(net "P3V3_SSD5_CO_MODE")
		)
		(pad "2" smd circle
			(at 0.40005 0 270)
			(size 0 0)
			(layers "F.Cu" "F.Mask" "F.Paste")
			(net "GND")
		)
	)
	(footprint ""
		(layer "F.Cu")
		(at 78.243684 -48.93691 180)
		(property "Reference" "R534"
			(at 0 0 180)
			(layer "F.SilkS")
			(hide yes)
			(effects
				(font
					(size 1.27 1.27)
				)
			)
		)
		(property "Value" ""
			(at 0 0 180)
			(layer "F.Fab")
			(effects
				(font
					(size 1.27 1.27)
				)
			)
		)
		(duplicate_pad_numbers_are_jumpers no)
		(fp_line
			(start 0.7874 0.4064)
			(end -0.7874 0.4064)
			(stroke
				(width 0.1524)
				(type default)
			)
			(layer "F.SilkS")
		)
		(fp_line
			(start 0.7874 -0.4064)
			(end 0.7874 0.4064)
			(stroke
				(width 0.1524)
				(type default)
			)
			(layer "F.SilkS")
		)
		(fp_line
			(start -0.7874 0.4064)
			(end -0.7874 -0.4064)
			(stroke
				(width 0.1524)
				(type default)
			)
			(layer "F.SilkS")
		)
		(fp_line
			(start -0.7874 -0.4064)
			(end 0.7874 -0.4064)
			(stroke
				(width 0.1524)
				(type default)
			)
			(layer "F.SilkS")
		)
		(fp_line
			(start 0.67945 0.3048)
			(end 0.120396 0.3048)
			(stroke
				(width 0.1)
				(type default)
			)
			(layer "F.Fab")
		)
		(fp_line
			(start 0.67945 -0.3048)
			(end 0.67945 0.3048)
			(stroke
				(width 0.1)
				(type default)
			)
			(layer "F.Fab")
		)
		(fp_line
			(start 0.12065 -0.2794)
			(end 0.12065 -0.3048)
			(stroke
				(width 0.1)
				(type default)
			)
			(layer "F.Fab")
		)
		(fp_line
			(start 0.12065 -0.3048)
			(end 0.67945 -0.3048)
			(stroke
				(width 0.1)
				(type default)
			)
			(layer "F.Fab")
		)
		(fp_line
			(start 0.120396 0.3048)
			(end 0.120396 0.2794)
			(stroke
				(width 0.1)
				(type default)
			)
			(layer "F.Fab")
		)
		(fp_line
			(start 0.120396 0.2794)
			(end -0.12065 0.2794)
			(stroke
				(width 0.1)
				(type default)
			)
			(layer "F.Fab")
		)
		(fp_line
			(start -0.12065 0.3048)
			(end -0.67945 0.3048)
			(stroke
				(width 0.1)
				(type default)
			)
			(layer "F.Fab")
		)
		(fp_line
			(start -0.12065 0.2794)
			(end -0.12065 0.3048)
			(stroke
				(width 0.1)
				(type default)
			)
			(layer "F.Fab")
		)
		(fp_line
			(start -0.12065 -0.2794)
			(end 0.12065 -0.2794)
			(stroke
				(width 0.1)
				(type default)
			)
			(layer "F.Fab")
		)
		(fp_line
			(start -0.12065 -0.305054)
			(end -0.12065 -0.2794)
			(stroke
				(width 0.1)
				(type default)
			)
			(layer "F.Fab")
		)
		(fp_line
			(start -0.67945 0.3048)
			(end -0.67945 -0.305054)
			(stroke
				(width 0.1)
				(type default)
			)
			(layer "F.Fab")
		)
		(fp_line
			(start -0.67945 -0.305054)
			(end -0.12065 -0.305054)
			(stroke
				(width 0.1)
				(type default)
			)
			(layer "F.Fab")
		)
		(pad "1" smd circle
			(at -0.40005 0 180)
			(size 0 0)
			(layers "F.Cu" "F.Mask" "F.Paste")
			(net "SMB_BIC_I2C6_MUX_SSD_0_7_ADC_R_SDA")
		)
		(pad "2" smd circle
			(at 0.40005 0 180)
			(size 0 0)
			(layers "F.Cu" "F.Mask" "F.Paste")
			(net "SMB_SSD2_ADC_SDA")
		)
	)
	(footprint ""
		(layer "F.Cu")
		(at 252.873002 -22.867366 90)
		(property "Reference" "C3928"
			(at 0 0 90)
			(layer "F.SilkS")
			(hide yes)
			(effects
				(font
					(size 1.27 1.27)
				)
			)
		)
		(property "Value" ""
			(at 0 0 90)
			(layer "F.Fab")
			(effects
				(font
					(size 1.27 1.27)
				)
			)
		)
		(duplicate_pad_numbers_are_jumpers no)
		(fp_line
			(start 0.7874 -0.4064)
			(end 0.7874 0.4064)
			(stroke
				(width 0.1524)
				(type default)
			)
			(layer "F.SilkS")
		)
		(fp_line
			(start -0.7874 -0.4064)
			(end 0.7874 -0.4064)
			(stroke
				(width 0.1524)
				(type default)
			)
			(layer "F.SilkS")
		)
		(fp_line
			(start 0.7874 0.4064)
			(end -0.7874 0.4064)
			(stroke
				(width 0.1524)
				(type default)
			)
			(layer "F.SilkS")
		)
		(fp_line
			(start -0.7874 0.4064)
			(end -0.7874 -0.4064)
			(stroke
				(width 0.1524)
				(type default)
			)
			(layer "F.SilkS")
		)
		(fp_line
			(start -0.12065 -0.305054)
			(end -0.12065 -0.2794)
			(stroke
				(width 0.1)
				(type default)
			)
			(layer "F.Fab")
		)
		(fp_line
			(start -0.67945 -0.305054)
			(end -0.12065 -0.305054)
			(stroke
				(width 0.1)
				(type default)
			)
			(layer "F.Fab")
		)
		(fp_line
			(start 0.67945 -0.3048)
			(end 0.67945 0.3048)
			(stroke
				(width 0.1)
				(type default)
			)
			(layer "F.Fab")
		)
		(fp_line
			(start 0.12065 -0.3048)
			(end 0.67945 -0.3048)
			(stroke
				(width 0.1)
				(type default)
			)
			(layer "F.Fab")
		)
		(fp_line
			(start 0.12065 -0.2794)
			(end 0.12065 -0.3048)
			(stroke
				(width 0.1)
				(type default)
			)
			(layer "F.Fab")
		)
		(fp_line
			(start -0.12065 -0.2794)
			(end 0.12065 -0.2794)
			(stroke
				(width 0.1)
				(type default)
			)
			(layer "F.Fab")
		)
		(fp_line
			(start 0.120396 0.2794)
			(end -0.12065 0.2794)
			(stroke
				(width 0.1)
				(type default)
			)
			(layer "F.Fab")
		)
		(fp_line
			(start -0.12065 0.2794)
			(end -0.12065 0.3048)
			(stroke
				(width 0.1)
				(type default)
			)
			(layer "F.Fab")
		)
		(fp_line
			(start 0.67945 0.3048)
			(end 0.120396 0.3048)
			(stroke
				(width 0.1)
				(type default)
			)
			(layer "F.Fab")
		)
		(fp_line
			(start 0.120396 0.3048)
			(end 0.120396 0.2794)
			(stroke
				(width 0.1)
				(type default)
			)
			(layer "F.Fab")
		)
		(fp_line
			(start -0.12065 0.3048)
			(end -0.67945 0.3048)
			(stroke
				(width 0.1)
				(type default)
			)
			(layer "F.Fab")
		)
		(fp_line
			(start -0.67945 0.3048)
			(end -0.67945 -0.305054)
			(stroke
				(width 0.1)
				(type default)
			)
			(layer "F.Fab")
		)
		(pad "1" smd circle
			(at -0.40005 0 90)
			(size 0 0)
			(layers "F.Cu" "F.Mask" "F.Paste")
			(net "P12V_SSD8")
		)
		(pad "2" smd circle
			(at 0.40005 0 90)
			(size 0 0)
			(layers "F.Cu" "F.Mask" "F.Paste")
			(net "GND")
		)
	)
	(footprint ""
		(layer "F.Cu")
		(at 45.471588 -25.342342 -90)
		(property "Reference" "R412"
			(at 0 0 270)
			(layer "F.SilkS")
			(hide yes)
			(effects
				(font
					(size 1.27 1.27)
				)
			)
		)
		(property "Value" ""
			(at 0 0 270)
			(layer "F.Fab")
			(effects
				(font
					(size 1.27 1.27)
				)
			)
		)
		(duplicate_pad_numbers_are_jumpers no)
		(fp_line
			(start -0.7874 0.4064)
			(end -0.7874 -0.4064)
			(stroke
				(width 0.1524)
				(type default)
			)
			(layer "F.SilkS")
		)
		(fp_line
			(start 0.7874 0.4064)
			(end -0.7874 0.4064)
			(stroke
				(width 0.1524)
				(type default)
			)
			(layer "F.SilkS")
		)
		(fp_line
			(start -0.7874 -0.4064)
			(end 0.7874 -0.4064)
			(stroke
				(width 0.1524)
				(type default)
			)
			(layer "F.SilkS")
		)
		(fp_line
			(start 0.7874 -0.4064)
			(end 0.7874 0.4064)
			(stroke
				(width 0.1524)
				(type default)
			)
			(layer "F.SilkS")
		)
		(fp_line
			(start -0.67945 0.3048)
			(end -0.67945 -0.305054)
			(stroke
				(width 0.1)
				(type default)
			)
			(layer "F.Fab")
		)
		(fp_line
			(start -0.12065 0.3048)
			(end -0.67945 0.3048)
			(stroke
				(width 0.1)
				(type default)
			)
			(layer "F.Fab")
		)
		(fp_line
			(start 0.120396 0.3048)
			(end 0.120396 0.2794)
			(stroke
				(width 0.1)
				(type default)
			)
			(layer "F.Fab")
		)
		(fp_line
			(start 0.67945 0.3048)
			(end 0.120396 0.3048)
			(stroke
				(width 0.1)
				(type default)
			)
			(layer "F.Fab")
		)
		(fp_line
			(start -0.12065 0.2794)
			(end -0.12065 0.3048)
			(stroke
				(width 0.1)
				(type default)
			)
			(layer "F.Fab")
		)
		(fp_line
			(start 0.120396 0.2794)
			(end -0.12065 0.2794)
			(stroke
				(width 0.1)
				(type default)
			)
			(layer "F.Fab")
		)
		(fp_line
			(start -0.12065 -0.2794)
			(end 0.12065 -0.2794)
			(stroke
				(width 0.1)
				(type default)
			)
			(layer "F.Fab")
		)
		(fp_line
			(start 0.12065 -0.2794)
			(end 0.12065 -0.3048)
			(stroke
				(width 0.1)
				(type default)
			)
			(layer "F.Fab")
		)
		(fp_line
			(start 0.12065 -0.3048)
			(end 0.67945 -0.3048)
			(stroke
				(width 0.1)
				(type default)
			)
			(layer "F.Fab")
		)
		(fp_line
			(start 0.67945 -0.3048)
			(end 0.67945 0.3048)
			(stroke
				(width 0.1)
				(type default)
			)
			(layer "F.Fab")
		)
		(fp_line
			(start -0.67945 -0.305054)
			(end -0.12065 -0.305054)
			(stroke
				(width 0.1)
				(type default)
			)
			(layer "F.Fab")
		)
		(fp_line
			(start -0.12065 -0.305054)
			(end -0.12065 -0.2794)
			(stroke
				(width 0.1)
				(type default)
			)
			(layer "F.Fab")
		)
		(pad "1" smd circle
			(at -0.40005 0 270)
			(size 0 0)
			(layers "F.Cu" "F.Mask" "F.Paste")
			(net "P3V3_SSD1")
		)
		(pad "2" smd circle
			(at 0.40005 0 270)
			(size 0 0)
			(layers "F.Cu" "F.Mask" "F.Paste")
			(net "DUALPORT_N_SSD1")
		)
	)
	(footprint ""
		(layer "F.Cu")
		(at 333.801212 -303.649634 90)
		(property "Reference" "PC150"
			(at 0 0 90)
			(layer "F.SilkS")
			(hide yes)
			(effects
				(font
					(size 1.27 1.27)
				)
			)
		)
		(property "Value" ""
			(at 0 0 90)
			(layer "F.Fab")
			(effects
				(font
					(size 1.27 1.27)
				)
			)
		)
		(duplicate_pad_numbers_are_jumpers no)
		(fp_line
			(start 1.524 -0.762)
			(end 1.524 0.762)
			(stroke
				(width 0.1524)
				(type default)
			)
			(layer "F.SilkS")
		)
		(fp_line
			(start -1.524 -0.762)
			(end 1.524 -0.762)
			(stroke
				(width 0.1524)
				(type default)
			)
			(layer "F.SilkS")
		)
		(fp_line
			(start 1.524 0.762)
			(end -1.524 0.762)
			(stroke
				(width 0.1524)
				(type default)
			)
			(layer "F.SilkS")
		)
		(fp_line
			(start -1.524 0.762)
			(end -1.524 -0.762)
			(stroke
				(width 0.1524)
				(type default)
			)
			(layer "F.SilkS")
		)
		(fp_line
			(start 1.1049 -0.724916)
			(end -1.1049 -0.724916)
			(stroke
				(width 0.1)
				(type default)
			)
			(layer "F.Fab")
		)
		(fp_line
			(start -1.1049 -0.724916)
			(end -1.1049 0.724916)
			(stroke
				(width 0.1)
				(type default)
			)
			(layer "F.Fab")
		)
		(fp_line
			(start 1.1049 0.724916)
			(end 1.1049 -0.724916)
			(stroke
				(width 0.1)
				(type default)
			)
			(layer "F.Fab")
		)
		(fp_line
			(start -1.1049 0.724916)
			(end 1.1049 0.724916)
			(stroke
				(width 0.1)
				(type default)
			)
			(layer "F.Fab")
		)
		(pad "1" smd rect
			(at -0.889 0 270)
			(size 1.016 1.27)
			(layers "F.Cu" "F.Mask" "F.Paste")
			(net "P0V8_PEX2")
		)
		(pad "2" smd rect
			(at 0.889 0 270)
			(size 1.016 1.27)
			(layers "F.Cu" "F.Mask" "F.Paste")
			(net "GND")
		)
	)
)
